# BASEBOARD_FAB2 (Tioga Pass) — schematic netlist excerpt (pin names and nets, part order shuffled) for the footprints in the layout excerpt that follows; sources: Cadence DE-HDL packaged netlist, KiCad conversion of Wiwynn_Tioga_Pass_MB.brd

R7D40  RES  0.0 5% EMPTY  pkg 0402  page 104 : A = FM_CPU0_VRM_OSC_EN ; B = FM_CPU0_STL_BRD_OSC_EN
C2T26  CAP_A  0.1UF 16V 10% X7R  pkg 0402V  page 185 : A = P3V3 ; B = GND
C9P23  CAPP  470UF 2.5V 20% ALUM  pkg 3018  page 208 : A = PVCCIN_CPU1 ; B = GND

(kicad_pcb
	(version 20260206)
	(generator "pcbnew")
	(generator_version "10.0")
	(general
		(thickness 1.6)
		(legacy_teardrops no)
	)
	(paper "A4")
	(title_block
		(title "Wiwynn_Tioga_Pass_MB.brd")
		(comment 1 "Tioga Pass / footprints 4398-4400 of 4770")
	)
	(layers
		(0 "F.Cu" signal "TOP")
		(4 "In1.Cu" signal "L2GND")
		(6 "In2.Cu" signal "L3")
		(8 "In3.Cu" signal "L4GND")
		(10 "In4.Cu" signal "L5")
		(12 "In5.Cu" signal "L6GND")
		(14 "In6.Cu" signal "L7VCC")
		(16 "In7.Cu" signal "L8VCC")
		(18 "In8.Cu" signal "L9GND")
		(20 "In9.Cu" signal "L10")
		(22 "In10.Cu" signal "L11GND")
		(24 "In11.Cu" signal "L12")
		(26 "In12.Cu" signal "L13GND")
		(2 "B.Cu" signal "BOTTOM")
		(9 "F.Adhes" user "F.Adhesive")
		(11 "B.Adhes" user "B.Adhesive")
		(13 "F.Paste" user "Package Geometry/Pastemask Top")
		(15 "B.Paste" user "Package Geometry/Pastemask Bottom")
		(5 "F.SilkS" user "Ref Des/Silkscreen Top")
		(7 "B.SilkS" user "Ref Des/Silkscreen Bottom")
		(1 "F.Mask" user "Board Geometry/Soldermask Top")
		(3 "B.Mask" user "Board Geometry/Soldermask Bottom")
		(17 "Dwgs.User" user "User.Drawings")
		(19 "Cmts.User" user "User.Comments")
		(21 "Eco1.User" user "User.Eco1")
		(23 "Eco2.User" user "User.Eco2")
		(25 "Edge.Cuts" user "Board Geometry/Outline")
		(27 "Margin" user)
		(31 "F.CrtYd" user "Package Geometry/Place Bound Top")
		(29 "B.CrtYd" user "Package Geometry/Place Bound Bottom")
		(35 "F.Fab" user "Ref Des/Assembly Top")
		(33 "B.Fab" user "Ref Des/Assembly Bottom")
	)
	(footprint ""
		(layer "B.Cu")
		(at 45.212 -67.945 -90)
		(property "Reference" "C9P23"
			(at 0.53467 -3.937 0)
			(unlocked yes)
			(layer "B.SilkS")
			(effects
				(font
					(size 0.7874 0.5842)
					(thickness 0.1524)
				)
				(justify mirror)
			)
		)
		(property "Value" ""
			(at 0 0 90)
			(layer "B.Fab")
			(effects
				(font
					(size 1.27 1.27)
				)
				(justify mirror)
			)
		)
		(duplicate_pad_numbers_are_jumpers no)
		(fp_line
			(start -2.286 7.366)
			(end -1.600708 7.366)
			(stroke
				(width 0.1524)
				(type default)
			)
			(layer "B.SilkS")
		)
		(fp_line
			(start -2.286 7.366)
			(end -2.286 1.63195)
			(stroke
				(width 0.1524)
				(type default)
			)
			(layer "B.SilkS")
		)
		(fp_line
			(start 2.286 7.366)
			(end 1.60147 7.366)
			(stroke
				(width 0.1524)
				(type default)
			)
			(layer "B.SilkS")
		)
		(fp_line
			(start 2.286 7.366)
			(end 2.286 1.632712)
			(stroke
				(width 0.1524)
				(type default)
			)
			(layer "B.SilkS")
		)
		(fp_line
			(start -2.504948 1.633728)
			(end -1.6002 1.633728)
			(stroke
				(width 0.1524)
				(type default)
			)
			(layer "B.SilkS")
		)
		(fp_line
			(start 2.563114 1.633728)
			(end 1.6002 1.633728)
			(stroke
				(width 0.1524)
				(type default)
			)
			(layer "B.SilkS")
		)
		(fp_line
			(start -2.504948 -1.616456)
			(end -2.504948 1.633728)
			(stroke
				(width 0.1524)
				(type default)
			)
			(layer "B.SilkS")
		)
		(fp_line
			(start -1.6002 -1.616456)
			(end -2.504948 -1.616456)
			(stroke
				(width 0.1524)
				(type default)
			)
			(layer "B.SilkS")
		)
		(fp_line
			(start 1.6002 -1.616456)
			(end 2.563114 -1.616456)
			(stroke
				(width 0.1524)
				(type default)
			)
			(layer "B.SilkS")
		)
		(fp_line
			(start 2.563114 -1.616456)
			(end 2.563114 1.633728)
			(stroke
				(width 0.1524)
				(type default)
			)
			(layer "B.SilkS")
		)
		(fp_rect
			(start 2.286 7.366)
			(end -2.286 -0.254)
			(stroke
				(width 0)
				(type default)
			)
			(fill no)
			(layer "B.CrtYd")
		)
		(fp_line
			(start -2.286 7.366)
			(end 2.286 7.366)
			(stroke
				(width 0.1)
				(type default)
			)
			(layer "B.Fab")
		)
		(fp_line
			(start 2.286 7.366)
			(end 2.286 -0.254)
			(stroke
				(width 0.1)
				(type default)
			)
			(layer "B.Fab")
		)
		(fp_line
			(start -2.286 -0.254)
			(end -2.286 7.366)
			(stroke
				(width 0.1)
				(type default)
			)
			(layer "B.Fab")
		)
		(fp_line
			(start 2.286 -0.254)
			(end -2.286 -0.254)
			(stroke
				(width 0.1)
				(type default)
			)
			(layer "B.Fab")
		)
		(pad "1" smd rect
			(at 0 0 90)
			(size 2.54 3.048)
			(layers "B.Cu" "B.Mask" "B.Paste")
			(net "PVCCIN_CPU1")
		)
		(pad "2" smd rect
			(at 0 7.112 90)
			(size 2.54 3.048)
			(layers "B.Cu" "B.Mask" "B.Paste")
			(net "GND")
		)
	)
	(footprint ""
		(layer "B.Cu")
		(at 390.635744 -22.543516 -90)
		(property "Reference" "C2T26"
			(at 0 0 90)
			(layer "B.SilkS")
			(hide yes)
			(effects
				(font
					(size 1.27 1.27)
				)
				(justify mirror)
			)
		)
		(property "Value" ""
			(at 0 0 90)
			(layer "B.Fab")
			(effects
				(font
					(size 1.27 1.27)
				)
				(justify mirror)
			)
		)
		(duplicate_pad_numbers_are_jumpers no)
		(fp_poly
			(pts
				(xy -0.3048 -0.1016) (xy -0.3048 0.9906) (xy 0.3048 0.9906) (xy 0.3048 -0.1016)
			)
			(stroke
				(width 0)
				(type default)
			)
			(fill no)
			(layer "B.CrtYd")
		)
		(fp_line
			(start -0.3048 0.9906)
			(end -0.3048 -0.1016)
			(stroke
				(width 0.1)
				(type default)
			)
			(layer "B.Fab")
		)
		(fp_line
			(start 0.3048 0.9906)
			(end -0.3048 0.9906)
			(stroke
				(width 0.1)
				(type default)
			)
			(layer "B.Fab")
		)
		(fp_line
			(start -0.3048 -0.1016)
			(end 0.3048 -0.1016)
			(stroke
				(width 0.1)
				(type default)
			)
			(layer "B.Fab")
		)
		(fp_line
			(start 0.3048 -0.1016)
			(end 0.3048 0.9906)
			(stroke
				(width 0.1)
				(type default)
			)
			(layer "B.Fab")
		)
		(pad "1" smd rect
			(at 0 0 90)
			(size 0.508 0.508)
			(layers "B.Cu" "B.Mask" "B.Paste")
			(net "P3V3")
		)
		(pad "2" smd rect
			(at 0 0.889 90)
			(size 0.508 0.508)
			(layers "B.Cu" "B.Mask" "B.Paste")
			(net "GND")
		)
		(zone
			(layer "B.Cu")
			(hatch none 0.5)
			(connect_pads
				(clearance 0)
			)
			(min_thickness 0.25)
			(keepout
				(tracks not_allowed)
				(vias allowed)
				(pads allowed)
				(copperpour not_allowed)
				(footprints allowed)
			)
			(placement
				(enabled no)
				(sheetname "")
			)
			(fill
				(thermal_gap 0.5)
				(thermal_bridge_width 0.5)
				(island_removal_mode 0)
			)
			(polygon
				(pts
					(xy 390.000744 -22.289516) (xy 390.000744 -22.797516) (xy 390.381744 -22.797516) (xy 390.381744 -22.289516)
				)
			)
		)
		(zone
			(layer "B.Cu")
			(hatch none 0.5)
			(connect_pads
				(clearance 0)
			)
			(min_thickness 0.25)
			(keepout
				(tracks allowed)
				(vias not_allowed)
				(pads allowed)
				(copperpour not_allowed)
				(footprints allowed)
			)
			(placement
				(enabled no)
				(sheetname "")
			)
			(fill
				(thermal_gap 0.5)
				(thermal_bridge_width 0.5)
				(island_removal_mode 0)
			)
			(polygon
				(pts
					(xy 390.381744 -22.289516) (xy 390.381744 -22.797516) (xy 390.000744 -22.797516) (xy 390.000744 -22.289516)
				)
			)
		)
	)
	(footprint ""
		(layer "B.Cu")
		(at 352.8949 -72.8218 -90)
		(property "Reference" "R7D40"
			(at 0 0 90)
			(layer "B.SilkS")
			(hide yes)
			(effects
				(font
					(size 1.27 1.27)
				)
				(justify mirror)
			)
		)
		(property "Value" ""
			(at 0 0 90)
			(layer "B.Fab")
			(effects
				(font
					(size 1.27 1.27)
				)
				(justify mirror)
			)
		)
		(duplicate_pad_numbers_are_jumpers no)
		(fp_poly
			(pts
				(xy 0.2794 -0.1016) (xy -0.2794 -0.1016) (xy -0.2794 0.9906) (xy 0.2794 0.9906)
			)
			(stroke
				(width 0)
				(type default)
			)
			(fill no)
			(layer "B.CrtYd")
		)
		(fp_line
			(start -0.2794 0.9906)
			(end -0.2794 -0.1016)
			(stroke
				(width 0.1)
				(type default)
			)
			(layer "B.Fab")
		)
		(fp_line
			(start 0.2794 0.9906)
			(end -0.2794 0.9906)
			(stroke
				(width 0.1)
				(type default)
			)
			(layer "B.Fab")
		)
		(fp_line
			(start -0.2794 -0.1016)
			(end 0.2794 -0.1016)
			(stroke
				(width 0.1)
				(type default)
			)
			(layer "B.Fab")
		)
		(fp_line
			(start 0.2794 -0.1016)
			(end 0.2794 0.9906)
			(stroke
				(width 0.1)
				(type default)
			)
			(layer "B.Fab")
		)
		(pad "1" smd rect
			(at 0 0 90)
			(size 0.508 0.508)
			(layers "B.Cu" "B.Mask" "B.Paste")
			(net "FM_CPU0_VRM_OSC_EN")
		)
		(pad "2" smd rect
			(at 0 0.889 90)
			(size 0.508 0.508)
			(layers "B.Cu" "B.Mask" "B.Paste")
			(net "FM_CPU0_STL_BRD_OSC_EN")
		)
		(zone
			(layer "B.Cu")
			(hatch none 0.5)
			(connect_pads
				(clearance 0)
			)
			(min_thickness 0.25)
			(keepout
				(tracks not_allowed)
				(vias allowed)
				(pads allowed)
				(copperpour not_allowed)
				(footprints allowed)
			)
			(placement
				(enabled no)
				(sheetname "")
			)
			(fill
				(thermal_gap 0.5)
				(thermal_bridge_width 0.5)
				(island_removal_mode 0)
			)
			(polygon
				(pts
					(xy 352.2599 -72.5678) (xy 352.2599 -73.0758) (xy 352.6409 -73.0758) (xy 352.6409 -72.5678)
				)
			)
		)
		(zone
			(layer "B.Cu")
			(hatch none 0.5)
			(connect_pads
				(clearance 0)
			)
			(min_thickness 0.25)
			(keepout
				(tracks allowed)
				(vias not_allowed)
				(pads allowed)
				(copperpour not_allowed)
				(footprints allowed)
			)
			(placement
				(enabled no)
				(sheetname "")
			)
			(fill
				(thermal_gap 0.5)
				(thermal_bridge_width 0.5)
				(island_removal_mode 0)
			)
			(polygon
				(pts
					(xy 352.6409 -72.5678) (xy 352.6409 -73.0758) (xy 352.2599 -73.0758) (xy 352.2599 -72.5678)
				)
			)
		)
	)
)
